# TIMECARD (Time Appliance Project (Time Card)) — schematic netlist excerpt (pin names and nets, part order shuffled) for the footprints in the layout excerpt that follows; sources: Cadence DE-HDL packaged netlist, KiCad conversion of R4006-B0001-02_R01.brd

J5  CONN_HDR_2X6_F_S_SMT  SMH-106-02-L-D-TR  pkg S_F_H_2X6_RA_P100  page 25
  \1\  = UNNAMED_16_CONNHDR2X6FSSMT_I161
  \2\  = UNNAMED_16_CONNHDR2X6FSSMT_I1_1
  \3\  = UNNAMED_16_CONNHDR2X6FSSMT_I1_2
  \4\  = UNNAMED_16_CONNHDR2X6FSSMT_I1_3
  \5\  = UNNAMED_16_CONNHDR2X6FSSMT_I1_6
  \6\  = UNNAMED_16_CONNHDR2X6FSSMT_I1_7
  \7\  = UNNAMED_16_CONNHDR2X6FSSMT_I1_4
  \8\  = UNNAMED_16_CONNHDR2X6FSSMT_I1_5
  \9\  = SG
  \10\  = SG
  \11\  = XP3R3V_FPGA
  \12\  = XP3R3V_FPGA

(kicad_pcb
	(version 20260206)
	(generator "pcbnew")
	(generator_version "10.0")
	(general
		(thickness 1.6)
		(legacy_teardrops no)
	)
	(paper "A4")
	(title_block
		(title "timecard-production-celestica-r4006 — R4006-B0001-02_R01.brd")
		(comment 1 "Time Appliance Project (Time Card) / footprints 490-490 of 1113")
	)
	(layers
		(0 "F.Cu" signal "TOP")
		(4 "In1.Cu" signal "L02_GND1")
		(6 "In2.Cu" signal "L03_SIG1")
		(8 "In3.Cu" signal "L04_GND2")
		(10 "In4.Cu" signal "L05_VCC1")
		(12 "In5.Cu" signal "L06_VCC2")
		(14 "In6.Cu" signal "L07_GND3")
		(16 "In7.Cu" signal "L08_SIG2")
		(18 "In8.Cu" signal "L09_GND4")
		(2 "B.Cu" signal "BOTTOM")
		(9 "F.Adhes" user "F.Adhesive")
		(11 "B.Adhes" user "B.Adhesive")
		(13 "F.Paste" user "Package Geometry/Pastemask Top")
		(15 "B.Paste" user "Package Geometry/Pastemask Bottom")
		(5 "F.SilkS" user "Ref Des/Silkscreen Top")
		(7 "B.SilkS" user "Ref Des/Silkscreen Bottom")
		(1 "F.Mask" user "Board Geometry/Soldermask Top")
		(3 "B.Mask" user "Board Geometry/Soldermask Bottom")
		(17 "Dwgs.User" user "User.Drawings")
		(19 "Cmts.User" user "User.Comments")
		(21 "Eco1.User" user "User.Eco1")
		(23 "Eco2.User" user "User.Eco2")
		(25 "Edge.Cuts" user "Board Geometry/Outline")
		(27 "Margin" user)
		(31 "F.CrtYd" user "Package Geometry/Place Bound Top")
		(29 "B.CrtYd" user "Package Geometry/Place Bound Bottom")
		(35 "F.Fab" user "Ref Des/Assembly Top")
		(33 "B.Fab" user "Ref Des/Assembly Bottom")
	)
	(footprint ""
		(layer "F.Cu")
		(at 163.395406 -38.624002 90)
		(property "Reference" "J5"
			(at -0.524002 -14.258036 90)
			(unlocked yes)
			(layer "F.SilkS")
			(effects
				(font
					(size 0.7874 0.5842)
					(thickness 0.1524)
				)
			)
		)
		(property "Value" ""
			(at 0 0 90)
			(layer "F.Fab")
			(effects
				(font
					(size 1.27 1.27)
				)
			)
		)
		(property "Device Type" "CONN_HDR_2X6_F_S_SMT-G200-1313A"
			(at 0 5.682996 90)
			(unlocked yes)
			(layer "F.Fab")
			(hide yes)
			(effects
				(font
					(size 0.7874 0.5842)
					(thickness 0.000001)
				)
			)
		)
		(property "User Part Number" "PARTNUM*"
			(at 0 6.876796 90)
			(unlocked yes)
			(layer "Cmts.User")
			(hide yes)
			(effects
				(font
					(size 0.7874 0.5842)
					(thickness 0.000001)
				)
			)
		)
		(duplicate_pad_numbers_are_jumpers no)
		(fp_line
			(start 8.253984 -12.506706)
			(end 8.253984 4.574032)
			(stroke
				(width 0.1)
				(type default)
			)
			(layer "F.SilkS")
		)
		(fp_line
			(start -8.253984 -12.506706)
			(end 8.253984 -12.506706)
			(stroke
				(width 0.1)
				(type default)
			)
			(layer "F.SilkS")
		)
		(fp_line
			(start 8.253984 4.574032)
			(end -8.253984 4.574032)
			(stroke
				(width 0.1)
				(type default)
			)
			(layer "F.SilkS")
		)
		(fp_line
			(start -8.253984 4.574032)
			(end -8.253984 -12.506706)
			(stroke
				(width 0.1)
				(type default)
			)
			(layer "F.SilkS")
		)
		(fp_rect
			(start -8.507984 4.828032)
			(end 8.507984 -12.760706)
			(stroke
				(width 0)
				(type default)
			)
			(fill no)
			(layer "F.CrtYd")
		)
		(fp_line
			(start 7.999984 -4.320032)
			(end 7.999984 4.320032)
			(stroke
				(width 0.1)
				(type default)
			)
			(layer "F.Fab")
		)
		(fp_line
			(start -7.999984 -4.320032)
			(end 7.999984 -4.320032)
			(stroke
				(width 0.1)
				(type default)
			)
			(layer "F.Fab")
		)
		(fp_line
			(start 7.999984 4.320032)
			(end -7.999984 4.320032)
			(stroke
				(width 0.1)
				(type default)
			)
			(layer "F.Fab")
		)
		(fp_line
			(start -7.999984 4.320032)
			(end -7.999984 -4.320032)
			(stroke
				(width 0.1)
				(type default)
			)
			(layer "F.Fab")
		)
		(fp_text user "12"
			(at -6.786372 -14.170406 0)
			(unlocked yes)
			(layer "F.SilkS")
			(effects
				(font
					(size 0.7874 0.5842)
					(thickness 0.1524)
				)
			)
		)
		(fp_text user "2"
			(at 8.746998 -10.702036 90)
			(unlocked yes)
			(layer "F.SilkS")
			(effects
				(font
					(size 0.7874 0.5842)
					(thickness 0.1524)
				)
			)
		)
		(fp_text user "1"
			(at 8.492998 -7.527036 90)
			(unlocked yes)
			(layer "F.SilkS")
			(effects
				(font
					(size 0.7874 0.5842)
					(thickness 0.1524)
				)
			)
		)
		(fp_text user "11"
			(at -9.199372 -6.804406 0)
			(unlocked yes)
			(layer "F.SilkS")
			(effects
				(font
					(size 0.7874 0.5842)
					(thickness 0.1524)
				)
			)
		)
		(fp_text user "12"
			(at -8.310372 -12.392406 0)
			(unlocked yes)
			(layer "F.Fab")
			(effects
				(font
					(size 0.7874 0.5842)
					(thickness 0.1524)
				)
			)
		)
		(fp_text user "2"
			(at 8.326628 -11.884406 0)
			(unlocked yes)
			(layer "F.Fab")
			(effects
				(font
					(size 0.7874 0.5842)
					(thickness 0.1524)
				)
			)
		)
		(fp_text user "1"
			(at 8.580628 -6.296406 0)
			(unlocked yes)
			(layer "F.Fab")
			(effects
				(font
					(size 0.7874 0.5842)
					(thickness 0.1524)
				)
			)
		)
		(fp_text user "11"
			(at -8.437372 -5.915406 0)
			(unlocked yes)
			(layer "F.Fab")
			(effects
				(font
					(size 0.7874 0.5842)
					(thickness 0.1524)
				)
			)
		)
		(pad "1" smd rect
			(at 6.35 -7.274814 90)
			(size 1.4224 2.3368)
			(layers "F.Cu" "F.Mask" "F.Paste")
			(net "UNNAMED_16_CONNHDR2X6FSSMT_I161")
		)
		(pad "2" smd rect
			(at 6.35 -11.135106 90)
			(size 1.4224 2.2352)
			(layers "F.Cu" "F.Mask" "F.Paste")
			(net "UNNAMED_16_CONNHDR2X6FSSMT_I1_1")
		)
		(pad "3" smd rect
			(at 3.81 -7.274814 90)
			(size 1.4224 2.3368)
			(layers "F.Cu" "F.Mask" "F.Paste")
			(net "UNNAMED_16_CONNHDR2X6FSSMT_I1_2")
		)
		(pad "4" smd rect
			(at 3.81 -11.135106 90)
			(size 1.4224 2.2352)
			(layers "F.Cu" "F.Mask" "F.Paste")
			(net "UNNAMED_16_CONNHDR2X6FSSMT_I1_3")
		)
		(pad "5" smd rect
			(at 1.27 -7.274814 90)
			(size 1.4224 2.3368)
			(layers "F.Cu" "F.Mask" "F.Paste")
			(net "UNNAMED_16_CONNHDR2X6FSSMT_I1_6")
		)
		(pad "6" smd rect
			(at 1.27 -11.135106 90)
			(size 1.4224 2.2352)
			(layers "F.Cu" "F.Mask" "F.Paste")
			(net "UNNAMED_16_CONNHDR2X6FSSMT_I1_7")
		)
		(pad "7" smd rect
			(at -1.27 -7.274814 90)
			(size 1.4224 2.3368)
			(layers "F.Cu" "F.Mask" "F.Paste")
			(net "UNNAMED_16_CONNHDR2X6FSSMT_I1_4")
		)
		(pad "8" smd rect
			(at -1.27 -11.135106 90)
			(size 1.4224 2.2352)
			(layers "F.Cu" "F.Mask" "F.Paste")
			(net "UNNAMED_16_CONNHDR2X6FSSMT_I1_5")
		)
		(pad "9" smd rect
			(at -3.81 -7.274814 90)
			(size 1.4224 2.3368)
			(layers "F.Cu" "F.Mask" "F.Paste")
			(net "SG")
		)
		(pad "10" smd rect
			(at -3.81 -11.135106 90)
			(size 1.4224 2.2352)
			(layers "F.Cu" "F.Mask" "F.Paste")
			(net "SG")
		)
		(pad "11" smd rect
			(at -6.35 -7.274814 90)
			(size 1.4224 2.3368)
			(layers "F.Cu" "F.Mask" "F.Paste")
			(net "XP3R3V_FPGA")
		)
		(pad "12" smd rect
			(at -6.35 -11.135106 90)
			(size 1.4224 2.2352)
			(layers "F.Cu" "F.Mask" "F.Paste")
			(net "XP3R3V_FPGA")
		)
	)
)
